(kicad_pcb
	(version 20260206)
	(generator "pcbnew")
	(generator_version "10.0")
	(general
		(thickness 1.6)
		(legacy_teardrops no)
	)
	(paper "A4")
	(title_block
		(title "12092022_DA0F0TMDCD0_F0T_Management_Board_D_brd_V3_OCP.brd")
		(comment 1 "Grand Teton / footprints 957-961 of 1440")
	)
	(layers
		(0 "F.Cu" signal "TOP")
		(4 "In1.Cu" signal "GND")
		(6 "In2.Cu" signal "IN1")
		(8 "In3.Cu" signal "GND1")
		(10 "In4.Cu" signal "IN2")
		(12 "In5.Cu" signal "VCC")
		(14 "In6.Cu" signal "VCC1")
		(16 "In7.Cu" signal "IN3")
		(18 "In8.Cu" signal "GND2")
		(20 "In9.Cu" signal "IN4")
		(22 "In10.Cu" signal "GND3")
		(2 "B.Cu" signal "BOTTOM")
		(9 "F.Adhes" user "F.Adhesive")
		(11 "B.Adhes" user "B.Adhesive")
		(13 "F.Paste" user "Package Geometry/Pastemask Top")
		(15 "B.Paste" user "Package Geometry/Pastemask Bottom")
		(5 "F.SilkS" user "Ref Des/Silkscreen Top")
		(7 "B.SilkS" user "Ref Des/Silkscreen Bottom")
		(1 "F.Mask" user "Board Geometry/Soldermask Top")
		(3 "B.Mask" user "Board Geometry/Soldermask Bottom")
		(17 "Dwgs.User" user "User.Drawings")
		(19 "Cmts.User" user "User.Comments")
		(21 "Eco1.User" user "User.Eco1")
		(23 "Eco2.User" user "User.Eco2")
		(25 "Edge.Cuts" user "Board Geometry/Outline")
		(27 "Margin" user)
		(31 "F.CrtYd" user "Package Geometry/Place Bound Top")
		(29 "B.CrtYd" user "Package Geometry/Place Bound Bottom")
		(35 "F.Fab" user "Ref Des/Assembly Top")
		(33 "B.Fab" user "Ref Des/Assembly Bottom")
	)
	(footprint ""
		(layer "B.Cu")
		(at 39.80053 -65.77965 -90)
		(property "Reference" "R189"
			(at 0 0 90)
			(layer "B.SilkS")
			(hide yes)
			(effects
				(font
					(size 1.27 1.27)
				)
				(justify mirror)
			)
		)
		(property "Value" ""
			(at 0 0 90)
			(layer "B.Fab")
			(effects
				(font
					(size 1.27 1.27)
				)
				(justify mirror)
			)
		)
		(duplicate_pad_numbers_are_jumpers no)
		(fp_line
			(start -0.7874 0.4064)
			(end 0.7874 0.4064)
			(stroke
				(width 0.1524)
				(type default)
			)
			(layer "B.SilkS")
		)
		(fp_line
			(start 0.7874 0.4064)
			(end 0.7874 -0.4064)
			(stroke
				(width 0.1524)
				(type default)
			)
			(layer "B.SilkS")
		)
		(fp_line
			(start -0.7874 -0.4064)
			(end -0.7874 0.4064)
			(stroke
				(width 0.1524)
				(type default)
			)
			(layer "B.SilkS")
		)
		(fp_line
			(start 0.7874 -0.4064)
			(end -0.7874 -0.4064)
			(stroke
				(width 0.1524)
				(type default)
			)
			(layer "B.SilkS")
		)
		(fp_line
			(start -0.67945 0.3048)
			(end -0.120396 0.3048)
			(stroke
				(width 0.1)
				(type default)
			)
			(layer "B.Fab")
		)
		(fp_line
			(start -0.120396 0.3048)
			(end -0.120396 0.2794)
			(stroke
				(width 0.1)
				(type default)
			)
			(layer "B.Fab")
		)
		(fp_line
			(start 0.12065 0.3048)
			(end 0.67945 0.3048)
			(stroke
				(width 0.1)
				(type default)
			)
			(layer "B.Fab")
		)
		(fp_line
			(start 0.67945 0.3048)
			(end 0.67945 -0.305054)
			(stroke
				(width 0.1)
				(type default)
			)
			(layer "B.Fab")
		)
		(fp_line
			(start -0.120396 0.2794)
			(end 0.12065 0.2794)
			(stroke
				(width 0.1)
				(type default)
			)
			(layer "B.Fab")
		)
		(fp_line
			(start 0.12065 0.2794)
			(end 0.12065 0.3048)
			(stroke
				(width 0.1)
				(type default)
			)
			(layer "B.Fab")
		)
		(fp_line
			(start -0.12065 -0.2794)
			(end -0.12065 -0.3048)
			(stroke
				(width 0.1)
				(type default)
			)
			(layer "B.Fab")
		)
		(fp_line
			(start 0.12065 -0.2794)
			(end -0.12065 -0.2794)
			(stroke
				(width 0.1)
				(type default)
			)
			(layer "B.Fab")
		)
		(fp_line
			(start -0.67945 -0.3048)
			(end -0.67945 0.3048)
			(stroke
				(width 0.1)
				(type default)
			)
			(layer "B.Fab")
		)
		(fp_line
			(start -0.12065 -0.3048)
			(end -0.67945 -0.3048)
			(stroke
				(width 0.1)
				(type default)
			)
			(layer "B.Fab")
		)
		(fp_line
			(start 0.12065 -0.305054)
			(end 0.12065 -0.2794)
			(stroke
				(width 0.1)
				(type default)
			)
			(layer "B.Fab")
		)
		(fp_line
			(start 0.67945 -0.305054)
			(end 0.12065 -0.305054)
			(stroke
				(width 0.1)
				(type default)
			)
			(layer "B.Fab")
		)
		(pad "1" smd circle
			(at 0.40005 0 90)
			(size 0 0)
			(layers "B.Cu" "B.Mask" "B.Paste")
			(net "P1V2_P1V0_I3C_VDDL1")
		)
		(pad "2" smd circle
			(at -0.40005 0 90)
			(size 0 0)
			(layers "B.Cu" "B.Mask" "B.Paste")
			(net "I3C3_SPD_SDA")
		)
	)
	(footprint ""
		(layer "B.Cu")
		(at 83.16722 -44.554394 180)
		(property "Reference" "R363"
			(at 0 0 0)
			(layer "B.SilkS")
			(hide yes)
			(effects
				(font
					(size 1.27 1.27)
				)
				(justify mirror)
			)
		)
		(property "Value" ""
			(at 0 0 0)
			(layer "B.Fab")
			(effects
				(font
					(size 1.27 1.27)
				)
				(justify mirror)
			)
		)
		(duplicate_pad_numbers_are_jumpers no)
		(fp_line
			(start 0.7874 0.4064)
			(end 0.7874 -0.4064)
			(stroke
				(width 0.1524)
				(type default)
			)
			(layer "B.SilkS")
		)
		(fp_line
			(start 0.7874 -0.4064)
			(end -0.7874 -0.4064)
			(stroke
				(width 0.1524)
				(type default)
			)
			(layer "B.SilkS")
		)
		(fp_line
			(start -0.7874 0.4064)
			(end 0.7874 0.4064)
			(stroke
				(width 0.1524)
				(type default)
			)
			(layer "B.SilkS")
		)
		(fp_line
			(start -0.7874 -0.4064)
			(end -0.7874 0.4064)
			(stroke
				(width 0.1524)
				(type default)
			)
			(layer "B.SilkS")
		)
		(fp_line
			(start 0.67945 0.3048)
			(end 0.67945 -0.305054)
			(stroke
				(width 0.1)
				(type default)
			)
			(layer "B.Fab")
		)
		(fp_line
			(start 0.67945 -0.305054)
			(end 0.12065 -0.305054)
			(stroke
				(width 0.1)
				(type default)
			)
			(layer "B.Fab")
		)
		(fp_line
			(start 0.12065 0.3048)
			(end 0.67945 0.3048)
			(stroke
				(width 0.1)
				(type default)
			)
			(layer "B.Fab")
		)
		(fp_line
			(start 0.12065 0.2794)
			(end 0.12065 0.3048)
			(stroke
				(width 0.1)
				(type default)
			)
			(layer "B.Fab")
		)
		(fp_line
			(start 0.12065 -0.2794)
			(end -0.12065 -0.2794)
			(stroke
				(width 0.1)
				(type default)
			)
			(layer "B.Fab")
		)
		(fp_line
			(start 0.12065 -0.305054)
			(end 0.12065 -0.2794)
			(stroke
				(width 0.1)
				(type default)
			)
			(layer "B.Fab")
		)
		(fp_line
			(start -0.120396 0.3048)
			(end -0.120396 0.2794)
			(stroke
				(width 0.1)
				(type default)
			)
			(layer "B.Fab")
		)
		(fp_line
			(start -0.120396 0.2794)
			(end 0.12065 0.2794)
			(stroke
				(width 0.1)
				(type default)
			)
			(layer "B.Fab")
		)
		(fp_line
			(start -0.12065 -0.2794)
			(end -0.12065 -0.3048)
			(stroke
				(width 0.1)
				(type default)
			)
			(layer "B.Fab")
		)
		(fp_line
			(start -0.12065 -0.3048)
			(end -0.67945 -0.3048)
			(stroke
				(width 0.1)
				(type default)
			)
			(layer "B.Fab")
		)
		(fp_line
			(start -0.67945 0.3048)
			(end -0.120396 0.3048)
			(stroke
				(width 0.1)
				(type default)
			)
			(layer "B.Fab")
		)
		(fp_line
			(start -0.67945 -0.3048)
			(end -0.67945 0.3048)
			(stroke
				(width 0.1)
				(type default)
			)
			(layer "B.Fab")
		)
		(pad "1" smd circle
			(at 0.40005 0)
			(size 0 0)
			(layers "B.Cu" "B.Mask" "B.Paste")
			(net "M_BMC_DDR4_MA<12>")
		)
		(pad "2" smd circle
			(at -0.40005 0)
			(size 0 0)
			(layers "B.Cu" "B.Mask" "B.Paste")
			(net "P1V2_AUX")
		)
	)
	(footprint ""
		(layer "B.Cu")
		(at 46.609 -107.3912)
		(property "Reference" "R79"
			(at 0 0 0)
			(layer "B.SilkS")
			(hide yes)
			(effects
				(font
					(size 1.27 1.27)
				)
				(justify mirror)
			)
		)
		(property "Value" ""
			(at 0 0 0)
			(layer "B.Fab")
			(effects
				(font
					(size 1.27 1.27)
				)
				(justify mirror)
			)
		)
		(duplicate_pad_numbers_are_jumpers no)
		(fp_line
			(start -0.7874 -0.4064)
			(end -0.7874 0.4064)
			(stroke
				(width 0.1524)
				(type default)
			)
			(layer "B.SilkS")
		)
		(fp_line
			(start -0.7874 0.4064)
			(end 0.7874 0.4064)
			(stroke
				(width 0.1524)
				(type default)
			)
			(layer "B.SilkS")
		)
		(fp_line
			(start 0.7874 -0.4064)
			(end -0.7874 -0.4064)
			(stroke
				(width 0.1524)
				(type default)
			)
			(layer "B.SilkS")
		)
		(fp_line
			(start 0.7874 0.4064)
			(end 0.7874 -0.4064)
			(stroke
				(width 0.1524)
				(type default)
			)
			(layer "B.SilkS")
		)
		(fp_line
			(start -0.67945 -0.3048)
			(end -0.67945 0.3048)
			(stroke
				(width 0.1)
				(type default)
			)
			(layer "B.Fab")
		)
		(fp_line
			(start -0.67945 0.3048)
			(end -0.120396 0.3048)
			(stroke
				(width 0.1)
				(type default)
			)
			(layer "B.Fab")
		)
		(fp_line
			(start -0.12065 -0.3048)
			(end -0.67945 -0.3048)
			(stroke
				(width 0.1)
				(type default)
			)
			(layer "B.Fab")
		)
		(fp_line
			(start -0.12065 -0.2794)
			(end -0.12065 -0.3048)
			(stroke
				(width 0.1)
				(type default)
			)
			(layer "B.Fab")
		)
		(fp_line
			(start -0.120396 0.2794)
			(end 0.12065 0.2794)
			(stroke
				(width 0.1)
				(type default)
			)
			(layer "B.Fab")
		)
		(fp_line
			(start -0.120396 0.3048)
			(end -0.120396 0.2794)
			(stroke
				(width 0.1)
				(type default)
			)
			(layer "B.Fab")
		)
		(fp_line
			(start 0.12065 -0.305054)
			(end 0.12065 -0.2794)
			(stroke
				(width 0.1)
				(type default)
			)
			(layer "B.Fab")
		)
		(fp_line
			(start 0.12065 -0.2794)
			(end -0.12065 -0.2794)
			(stroke
				(width 0.1)
				(type default)
			)
			(layer "B.Fab")
		)
		(fp_line
			(start 0.12065 0.2794)
			(end 0.12065 0.3048)
			(stroke
				(width 0.1)
				(type default)
			)
			(layer "B.Fab")
		)
		(fp_line
			(start 0.12065 0.3048)
			(end 0.67945 0.3048)
			(stroke
				(width 0.1)
				(type default)
			)
			(layer "B.Fab")
		)
		(fp_line
			(start 0.67945 -0.305054)
			(end 0.12065 -0.305054)
			(stroke
				(width 0.1)
				(type default)
			)
			(layer "B.Fab")
		)
		(fp_line
			(start 0.67945 0.3048)
			(end 0.67945 -0.305054)
			(stroke
				(width 0.1)
				(type default)
			)
			(layer "B.Fab")
		)
		(pad "1" smd circle
			(at 0.40005 0 180)
			(size 0 0)
			(layers "B.Cu" "B.Mask" "B.Paste")
			(net "P3V3_AUX")
		)
		(pad "2" smd circle
			(at -0.40005 0 180)
			(size 0 0)
			(layers "B.Cu" "B.Mask" "B.Paste")
			(net "SGPIO_DO_0")
		)
	)
	(footprint ""
		(layer "B.Cu")
		(at 80.546194 -53.342286 90)
		(property "Reference" "C9"
			(at 0 0 90)
			(layer "B.SilkS")
			(hide yes)
			(effects
				(font
					(size 1.27 1.27)
				)
				(justify mirror)
			)
		)
		(property "Value" ""
			(at 0 0 90)
			(layer "B.Fab")
			(effects
				(font
					(size 1.27 1.27)
				)
				(justify mirror)
			)
		)
		(duplicate_pad_numbers_are_jumpers no)
		(fp_line
			(start 0.7874 -0.4064)
			(end -0.7874 -0.4064)
			(stroke
				(width 0.1524)
				(type default)
			)
			(layer "B.SilkS")
		)
		(fp_line
			(start -0.7874 -0.4064)
			(end -0.7874 0.4064)
			(stroke
				(width 0.1524)
				(type default)
			)
			(layer "B.SilkS")
		)
		(fp_line
			(start 0.7874 0.4064)
			(end 0.7874 -0.4064)
			(stroke
				(width 0.1524)
				(type default)
			)
			(layer "B.SilkS")
		)
		(fp_line
			(start -0.7874 0.4064)
			(end 0.7874 0.4064)
			(stroke
				(width 0.1524)
				(type default)
			)
			(layer "B.SilkS")
		)
		(fp_line
			(start 0.67945 -0.305054)
			(end 0.12065 -0.305054)
			(stroke
				(width 0.1)
				(type default)
			)
			(layer "B.Fab")
		)
		(fp_line
			(start 0.12065 -0.305054)
			(end 0.12065 -0.2794)
			(stroke
				(width 0.1)
				(type default)
			)
			(layer "B.Fab")
		)
		(fp_line
			(start -0.12065 -0.3048)
			(end -0.67945 -0.3048)
			(stroke
				(width 0.1)
				(type default)
			)
			(layer "B.Fab")
		)
		(fp_line
			(start -0.67945 -0.3048)
			(end -0.67945 0.3048)
			(stroke
				(width 0.1)
				(type default)
			)
			(layer "B.Fab")
		)
		(fp_line
			(start 0.12065 -0.2794)
			(end -0.12065 -0.2794)
			(stroke
				(width 0.1)
				(type default)
			)
			(layer "B.Fab")
		)
		(fp_line
			(start -0.12065 -0.2794)
			(end -0.12065 -0.3048)
			(stroke
				(width 0.1)
				(type default)
			)
			(layer "B.Fab")
		)
		(fp_line
			(start 0.12065 0.2794)
			(end 0.12065 0.3048)
			(stroke
				(width 0.1)
				(type default)
			)
			(layer "B.Fab")
		)
		(fp_line
			(start -0.120396 0.2794)
			(end 0.12065 0.2794)
			(stroke
				(width 0.1)
				(type default)
			)
			(layer "B.Fab")
		)
		(fp_line
			(start 0.67945 0.3048)
			(end 0.67945 -0.305054)
			(stroke
				(width 0.1)
				(type default)
			)
			(layer "B.Fab")
		)
		(fp_line
			(start 0.12065 0.3048)
			(end 0.67945 0.3048)
			(stroke
				(width 0.1)
				(type default)
			)
			(layer "B.Fab")
		)
		(fp_line
			(start -0.120396 0.3048)
			(end -0.120396 0.2794)
			(stroke
				(width 0.1)
				(type default)
			)
			(layer "B.Fab")
		)
		(fp_line
			(start -0.67945 0.3048)
			(end -0.120396 0.3048)
			(stroke
				(width 0.1)
				(type default)
			)
			(layer "B.Fab")
		)
		(pad "1" smd circle
			(at 0.40005 0 270)
			(size 0 0)
			(layers "B.Cu" "B.Mask" "B.Paste")
			(net "P1V2_AUX")
		)
		(pad "2" smd circle
			(at -0.40005 0 270)
			(size 0 0)
			(layers "B.Cu" "B.Mask" "B.Paste")
			(net "GND")
		)
	)
	(footprint ""
		(layer "B.Cu")
		(at 43.890184 -101.70287)
		(property "Reference" "U21"
			(at 0.369316 3.44424 0)
			(unlocked yes)
			(layer "B.SilkS")
			(effects
				(font
					(size 0.7874 0.5842)
					(thickness 0.1524)
				)
				(justify left mirror)
			)
		)
		(property "Value" ""
			(at 0 0 0)
			(layer "B.Fab")
			(effects
				(font
					(size 1.27 1.27)
				)
				(justify mirror)
			)
		)
		(duplicate_pad_numbers_are_jumpers no)
		(fp_line
			(start -2.0066 -2.5654)
			(end -2.0066 2.5654)
			(stroke
				(width 0.1524)
				(type default)
			)
			(layer "B.SilkS")
		)
		(fp_line
			(start -2.0066 2.5654)
			(end 2.0066 2.5654)
			(stroke
				(width 0.1524)
				(type default)
			)
			(layer "B.SilkS")
		)
		(fp_line
			(start -0.5842 -2.5654)
			(end -2.0066 -2.5654)
			(stroke
				(width 0.1524)
				(type default)
			)
			(layer "B.SilkS")
		)
		(fp_line
			(start 0 -1.9812)
			(end -0.5842 -2.5654)
			(stroke
				(width 0.1524)
				(type default)
			)
			(layer "B.SilkS")
		)
		(fp_line
			(start 0.5842 -2.5654)
			(end 0 -1.9812)
			(stroke
				(width 0.1524)
				(type default)
			)
			(layer "B.SilkS")
		)
		(fp_line
			(start 2.0066 -2.5654)
			(end 0.5842 -2.5654)
			(stroke
				(width 0.1524)
				(type default)
			)
			(layer "B.SilkS")
		)
		(fp_line
			(start 2.0066 2.5654)
			(end 2.0066 -2.5654)
			(stroke
				(width 0.1524)
				(type default)
			)
			(layer "B.SilkS")
		)
		(fp_poly
			(pts
				(xy 3.853688 -2.300478) (xy 4.869688 -2.808478) (xy 4.869688 -1.792478)
			)
			(stroke
				(width 0)
				(type default)
			)
			(fill yes)
			(layer "B.SilkS")
		)
		(fp_line
			(start -3.7338 -2.5654)
			(end -3.6703 -2.5654)
			(stroke
				(width 0.1)
				(type default)
			)
			(layer "B.Fab")
		)
		(fp_line
			(start -3.7338 2.5654)
			(end -3.7338 -2.5654)
			(stroke
				(width 0.1)
				(type default)
			)
			(layer "B.Fab")
		)
		(fp_line
			(start -3.6703 -2.5654)
			(end 3.6703 -2.5654)
			(stroke
				(width 0.1)
				(type default)
			)
			(layer "B.Fab")
		)
		(fp_line
			(start -3.6703 2.5654)
			(end -3.7338 2.5654)
			(stroke
				(width 0.1)
				(type default)
			)
			(layer "B.Fab")
		)
		(fp_line
			(start 3.6703 -2.5654)
			(end 3.7338 -2.5654)
			(stroke
				(width 0.1)
				(type default)
			)
			(layer "B.Fab")
		)
		(fp_line
			(start 3.6703 2.5654)
			(end -3.6703 2.5654)
			(stroke
				(width 0.1)
				(type default)
			)
			(layer "B.Fab")
		)
		(fp_line
			(start 3.7338 -2.5654)
			(end 3.7338 2.5654)
			(stroke
				(width 0.1)
				(type default)
			)
			(layer "B.Fab")
		)
		(fp_line
			(start 3.7338 2.5654)
			(end 3.6703 2.5654)
			(stroke
				(width 0.1)
				(type default)
			)
			(layer "B.Fab")
		)
		(fp_poly
			(pts
				(xy 3.955288 -2.275078) (xy 4.971288 -2.783078) (xy 4.971288 -1.767078)
			)
			(stroke
				(width 0)
				(type default)
			)
			(fill yes)
			(layer "B.Fab")
		)
		(pad "1" smd rect
			(at 2.921 -2.275078 270)
			(size 0.3556 1.4986)
			(layers "B.Cu" "B.Mask" "B.Paste")
			(net "FM_BMC_BIOS_MUX_CS_SPI_R_SEL_0")
		)
		(pad "2" smd rect
			(at 2.921 -1.625092 270)
			(size 0.3556 1.4986)
			(layers "B.Cu" "B.Mask" "B.Paste")
			(net "SPI_SYS_MUX_WP_IO2")
		)
		(pad "3" smd rect
			(at 2.921 -0.975106 270)
			(size 0.3556 1.4986)
			(layers "B.Cu" "B.Mask" "B.Paste")
			(net "SPI_BMC_BIOS_ROM_R_IO2")
		)
		(pad "4" smd rect
			(at 2.921 -0.32512 270)
			(size 0.3556 1.4986)
			(layers "B.Cu" "B.Mask" "B.Paste")
			(net "SPI_PCH_MUXED_IO2")
		)
		(pad "5" smd rect
			(at 2.921 0.32512 270)
			(size 0.3556 1.4986)
			(layers "B.Cu" "B.Mask" "B.Paste")
			(net "SPI_SYS_MUX_MISO")
		)
		(pad "6" smd rect
			(at 2.921 0.975106 270)
			(size 0.3556 1.4986)
			(layers "B.Cu" "B.Mask" "B.Paste")
			(net "SPI_BMC_BIOS_ROM_R_MISO")
		)
		(pad "7" smd rect
			(at 2.921 1.625092 270)
			(size 0.3556 1.4986)
			(layers "B.Cu" "B.Mask" "B.Paste")
			(net "SPI_PCH_MUXED_IO1")
		)
		(pad "8" smd rect
			(at 2.921 2.275078 270)
			(size 0.3556 1.4986)
			(layers "B.Cu" "B.Mask" "B.Paste")
			(net "GND")
		)
		(pad "9" smd rect
			(at -2.921 2.275078 270)
			(size 0.3556 1.4986)
			(layers "B.Cu" "B.Mask" "B.Paste")
			(net "SPI_PCH_MUXED_CS0_N")
		)
		(pad "10" smd rect
			(at -2.921 1.625092 270)
			(size 0.3556 1.4986)
			(layers "B.Cu" "B.Mask" "B.Paste")
			(net "SPI_BMC_BIOS_SOURCE_CS0_N")
		)
		(pad "11" smd rect
			(at -2.921 0.975106 270)
			(size 0.3556 1.4986)
			(layers "B.Cu" "B.Mask" "B.Paste")
			(net "SPI_PCH_SECURE_CS0_N")
		)
		(pad "12" smd rect
			(at -2.921 0.32512 270)
			(size 0.3556 1.4986)
			(layers "B.Cu" "B.Mask" "B.Paste")
			(net "TP_BIOS_MUX1_PIN12")
		)
		(pad "13" smd rect
			(at -2.921 -0.32512 270)
			(size 0.3556 1.4986)
			(layers "B.Cu" "B.Mask" "B.Paste")
			(net "TP_BIOS_MUX1_PIN13")
		)
		(pad "14" smd rect
			(at -2.921 -0.975106 270)
			(size 0.3556 1.4986)
			(layers "B.Cu" "B.Mask" "B.Paste")
			(net "TP_BIOS_MUX1_PIN14")
		)
		(pad "15" smd rect
			(at -2.921 -1.625092 270)
			(size 0.3556 1.4986)
			(layers "B.Cu" "B.Mask" "B.Paste")
			(net "PD_BIOS_MUX_EN_N")
		)
		(pad "16" smd rect
			(at -2.921 -2.275078 270)
			(size 0.3556 1.4986)
			(layers "B.Cu" "B.Mask" "B.Paste")
			(net "P3V3_AUX")
		)
	)
)
